FILE_TYPE = MULTI_PHYS_TABLE;
PART 'INDUCTOR'
{========================================================================================}
:VALUE     | PACK_TYPE | MATERIAL | PART_NUMBER    = ENVCOMP                            | PART_NUMBER   | JEDEC_TYPE    | ALT_SYMBOLS                   | VALUE     | CLASS      | DESCRIPTION                                        | COMPONENT_TYPE | HEIGHT     | LEAD_LENGTH | LPID   | SPEED_URL                                                                                                                        | STATUS        | RPL   | AML  | BUS_UNIT        | DAYS  ;
{========================================================================================}
'0.022uH' | 'SMT'     | 'IND'    | '721891-082'(!) = ''                                 | '721891-082'  | 'SMI0805D'    | '(SMX0805)'                   | '0.022UH' | 'DISCRETE' | 'INDCT,MTILAYER,22.00nH,1.85A,0805,10.00%'         | 'CHIP0805'     | '0.039 IN' | ''          | '2375' | 'http://speed.intel.com:8081/speed/module/pdm/item/pdm_item_detail_direct.asp?item_cde=721891-082&item_rev=01&url_param=unused'  | ''            | ''    | ''   | ''              | ''   
'0.022uH' | 'SMT'     | 'EMPTY'  | '721891-082'(!) = ''                                 | '721891-082'  | 'SMI0805D'    | '(SMX0805)'                   | 'NA'      | 'DISCRETE' | 'INDCT,MTILAYER,22.00nH,1.85A,0805,10.00%'         | 'CHIP0805'     | '0.039 IN' | ''          | '2375' | 'http://speed.intel.com:8081/speed/module/pdm/item/pdm_item_detail_direct.asp?item_cde=721891-082&item_rev=01&url_param=unused'  | ''            | ''    | ''   | ''              | ''   
'100NH'   | 'SM'      | 'IND'    | 'D92183-020'(!) = 'YES;YES;YES;UNK;OK;VLD'           | 'D92183-020'  | 'SMI1516A'    | ''                            | '100NH'   | 'DISCRETE' | 'INDCT,0.1UH,19.0A,0.32MOHM,CUBE,SM'               | 'SMTOTHER'     | '0.157 IN' | ''          | '2345' | 'http://speed.intel.com:8081/speed/module/pdm/item/pdm_item_detail_direct.asp?item_cde=D92183-020&item_rev=01&url_param=unused'  | 'DESIGN'      | 'YES' | '2'  | 'SMO_BOARDS'    | '???'
'100NH'   | 'SM'      | 'EMPTY'  | 'D92183-020'(!) = 'YES;YES;YES;UNK;OK;VLD'           | 'D92183-020'  | 'SMI1516A'    | ''                            | 'NA'      | 'DISCRETE' | 'INDCT,0.1UH,19.0A,0.32MOHM,CUBE,SM'               | 'SMTOTHER'     | '0.157 IN' | ''          | '2345' | 'http://speed.intel.com:8081/speed/module/pdm/item/pdm_item_detail_direct.asp?item_cde=D92183-020&item_rev=01&url_param=unused'  | 'DESIGN'      | 'YES' | '2'  | 'SMO_BOARDS'    | '???'
'100NH'   | 'SM'      | 'IND'    | 'D92183-019'(!) = 'YES;YES;YES;UNK;OK;VLD'           | 'D92183-019'  | 'SMI2020D'    | ''                            | '100NH'   | 'DISCRETE' | 'INDCT,0.1UH,29.0A,0.47MOHM,CUBE,SM'               | 'SMTOTHER'     | '0.260 IN' | ''          | '2343' | 'http://speed.intel.com:8081/speed/module/pdm/item/pdm_item_detail_direct.asp?item_cde=D92183-019&item_rev=01&url_param=unused'  | 'DESIGN'      | 'YES' | '1'  | 'SMO_BOARDS'    | '???'
'100NH'   | 'SM'      | 'EMPTY'  | 'D92183-019'(!) = 'YES;YES;YES;UNK;OK;VLD'           | 'D92183-019'  | 'SMI2020D'    | ''                            | 'NA'      | 'DISCRETE' | 'INDCT,0.1UH,29.0A,0.47MOHM,CUBE,SM'               | 'SMTOTHER'     | '0.260 IN' | ''          | '2343' | 'http://speed.intel.com:8081/speed/module/pdm/item/pdm_item_detail_direct.asp?item_cde=D92183-019&item_rev=01&url_param=unused'  | 'DESIGN'      | 'YES' | '1'  | 'SMO_BOARDS'    | '???'
'0.47UH'  | 'SM'      | 'IND'    | 'E13358-018'(!) = 'YES;YES;YES;UNK;OK;VLD'           | 'E13358-018'  | 'SMI2626A'    | ''                            | '0.47UH'  | 'DISCRETE' | 'INDUCTOR 0.47UH'                                  | 'SMTOTHER'     | '0.118 IN' | ''          | '2139' | 'http://speed.intel.com:8081/speed/module/pdm/item/pdm_item_detail_direct.asp?item_cde=E13358-018&item_rev=01&url_param=unused'  | 'UNQUAL'      | 'YES' | '3'  | 'SMO_BOARDS'    | '???'
'0.47UH'  | 'SM'      | 'EMPTY'  | 'E13358-018'(!) = 'YES;YES;YES;UNK;OK;VLD'           | 'E13358-018'  | 'SMI2626A'    | ''                            | 'NA'      | 'DISCRETE' | 'INDUCTOR 0.47UH'                                  | 'SMTOTHER'     | '0.118 IN' | ''          | '2139' | 'http://speed.intel.com:8081/speed/module/pdm/item/pdm_item_detail_direct.asp?item_cde=E13358-018&item_rev=01&url_param=unused'  | 'UNQUAL'      | 'YES' | '3'  | 'SMO_BOARDS'    | '???'
'2.2UH'   | 'SM'      | 'IND'    | 'E98761-003'(!) = 'YES;YES;YES;UNK;OK;VLD'           | 'E98761-003'  | 'SMI2626A'    | ''                            | '2.2UH'   | 'DISCRETE' | 'INDUCTOR 2.2UH'                                   | 'SMTOTHER'     | '0.118 IN' | ''          | '2139' | 'http://speed.intel.com:8081/speed/module/pdm/item/pdm_item_detail_direct.asp?item_cde=E98761-003&item_rev=01&url_param=unused'  | 'DESIGN'      | 'NO'  | '4'  | 'SMO_BOARDS'    | '???'
'2.2UH'   | 'SM'      | 'EMPTY'  | 'E98761-003'(!) = 'YES;YES;YES;UNK;OK;VLD'           | 'E98761-003'  | 'SMI2626A'    | ''                            | 'NA'      | 'DISCRETE' | 'INDUCTOR 2.2UH'                                   | 'SMTOTHER'     | '0.118 IN' | ''          | '2139' | 'http://speed.intel.com:8081/speed/module/pdm/item/pdm_item_detail_direct.asp?item_cde=E98761-003&item_rev=01&url_param=unused'  | 'DESIGN'      | 'NO'  | '4'  | 'SMO_BOARDS'    | '???'
'150NH'   | 'SM'      | 'IND'    | 'D92183-021'(!) = 'YES;YES;YES;UNK;OK;VLD'           | 'D92183-021'  | 'SMI3725A'    | ''                            | '150NH'   | 'DISCRETE' | 'INDCT,0.15UH,57.0A,0.29MOHM,CUBE,SM'              | 'SMTOTHER'     | '0.315 IN' | ''          | '2342' | 'http://speed.intel.com:8081/speed/module/pdm/item/pdm_item_detail_direct.asp?item_cde=D92183-021&item_rev=01&url_param=unused'  | 'DESIGN'      | 'YES' | '1'  | 'SMO_BOARDS'    | '???'
'150NH'   | 'SM'      | 'EMPTY'  | 'D92183-021'(!) = 'YES;YES;YES;UNK;OK;VLD'           | 'D92183-021'  | 'SMI3725A'    | ''                            | 'NA'      | 'DISCRETE' | 'INDCT,0.15UH,57.0A,0.29MOHM,CUBE,SM'              | 'SMTOTHER'     | '0.315 IN' | ''          | '2342' | 'http://speed.intel.com:8081/speed/module/pdm/item/pdm_item_detail_direct.asp?item_cde=D92183-021&item_rev=01&url_param=unused'  | 'DESIGN'      | 'YES' | '1'  | 'SMO_BOARDS'    | '???'
'0.12UH'  | 'SM'      | 'IND'    | 'D92183-034'(!) = 'YES;YES;YES;UNK;OK;VLD'           | 'D92183-034'  | 'SMI3725A'    | ''                            | '0.12UH'  | 'DISCRETE' | 'INDCT,0.12UH,70.0A,0.29MOHM,CUBE,SM'              | 'SMTOTHER'     | '0.315 IN' | ''          | '2342' | 'http://speed.intel.com:8081/speed/module/pdm/item/pdm_item_detail_direct.asp?item_cde=D92183-034&item_rev=01&url_param=unused'  | 'DESIGN'      | 'YES' | '1'  | 'SMO_BOARDS'    | '???'
'0.12UH'  | 'SM'      | 'EMPTY'  | 'D92183-034'(!) = 'YES;YES;YES;UNK;OK;VLD'           | 'D92183-034'  | 'SMI3725A'    | ''                            | 'NA'      | 'DISCRETE' | 'INDCT,0.12UH,70.0A,0.29MOHM,CUBE,SM'              | 'SMTOTHER'     | '0.315 IN' | ''          | '2342' | 'http://speed.intel.com:8081/speed/module/pdm/item/pdm_item_detail_direct.asp?item_cde=D92183-034&item_rev=01&url_param=unused'  | 'DESIGN'      | 'YES' | '1'  | 'SMO_BOARDS'    | '???'
'0.3UH'   | 'SM'      | 'IND'    | 'D92183-036'(!) = 'YES;YES;YES;UNK;OK;VLD'           | 'D92183-036'  | 'SMI3725A'    | ''                            | '0.3UH'   | 'DISCRETE' | 'INDCT,0.3UH,51.0A,0.29MOHM,CUBE,SM'               | 'SMTOTHER'     | '0.315 IN' | ''          | '2342' | 'http://speed.intel.com:8081/speed/module/pdm/item/pdm_item_detail_direct.asp?item_cde=D92183-036&item_rev=01&url_param=unused'  | 'DESIGN'      | 'YES' | '1'  | 'SMO_BOARDS'    | '???'
'0.3UH'   | 'SM'      | 'EMPTY'  | 'D92183-036'(!) = 'YES;YES;YES;UNK;OK;VLD'           | 'D92183-036'  | 'SMI3725A'    | ''                            | 'NA'      | 'DISCRETE' | 'INDCT,0.3UH,51.0A,0.29MOHM,CUBE,SM'               | 'SMTOTHER'     | '0.315 IN' | ''          | '2342' | 'http://speed.intel.com:8081/speed/module/pdm/item/pdm_item_detail_direct.asp?item_cde=D92183-036&item_rev=01&url_param=unused'  | 'DESIGN'      | 'YES' | '1'  | 'SMO_BOARDS'    | '???'
'1.00UH'  | 'SM'      | 'IND'    | 'E98679-006'(!) = 'UNK;UNK;UNK;UNK;OK;CIP'           | 'E98679-006'  | 'SMI4040A'    | ''                            | '1.00UH'  | 'DISCRETE' | 'INDCT,1.00UH,22.0A,2.7MOHM,CUBE,SM'               | 'SMTOTHER'     | '0.177 IN' | ''          | '1452' | 'http://speed.intel.com:8081/speed/module/pdm/item/pdm_item_detail_direct.asp?item_cde=E98679-006&item_rev=01&url_param=unused'  | 'DESIGN'      | 'NO'  | '1'  | 'SMO_BOARDS'    | '???'
'1.00UH'  | 'SM'      | 'EMPTY'  | 'E98679-006'(!) = 'UNK;UNK;UNK;UNK;OK;CIP'           | 'E98679-006'  | 'SMI4040A'    | ''                            | 'NA'      | 'DISCRETE' | 'INDCT,1.00UH,22.0A,2.7MOHM,CUBE,SM'               | 'SMTOTHER'     | '0.177 IN' | ''          | '1452' | 'http://speed.intel.com:8081/speed/module/pdm/item/pdm_item_detail_direct.asp?item_cde=E98679-006&item_rev=01&url_param=unused'  | 'DESIGN'      | 'NO'  | '1'  | 'SMO_BOARDS'    | '???'
END_PART
END.
